# T6G (Grand Teton) — schematic netlist excerpt (pin names and nets, part order shuffled) for the footprints in the layout excerpt that follows; sources: Cadence DE-HDL packaged netlist, KiCad conversion of 04192023_DAF0TMB3IC0_F0TG_MB_C_brd_V02_OCP.brd

C2141  Q_CAP  22UF 4V 20% X6S  pkg C0402  page 68 : A = PVDDIO_P0 ; B = GND
PC6632  Q_CAPP  390UF 2.5V 20% ALUM  pkg SMLF  page 365 : A = P0V9_CPU1_RT_2D ; B = GND

(kicad_pcb
	(version 20260206)
	(generator "pcbnew")
	(generator_version "10.0")
	(general
		(thickness 1.6)
		(legacy_teardrops no)
	)
	(paper "A4")
	(title_block
		(title "04192023_DAF0TMB3IC0_F0TG_MB_C_brd_V02_OCP.brd")
		(comment 1 "Grand Teton / footprints 2387-2388 of 8354")
	)
	(layers
		(0 "F.Cu" signal "TOP")
		(4 "In1.Cu" signal "GND")
		(6 "In2.Cu" signal "IN1")
		(8 "In3.Cu" signal "GND1")
		(10 "In4.Cu" signal "IN2")
		(12 "In5.Cu" signal "GND2")
		(14 "In6.Cu" signal "IN3")
		(16 "In7.Cu" signal "GND3")
		(18 "In8.Cu" signal "VCC")
		(20 "In9.Cu" signal "VCC1")
		(22 "In10.Cu" signal "GND4")
		(24 "In11.Cu" signal "IN4")
		(26 "In12.Cu" signal "GND5")
		(28 "In13.Cu" signal "IN5")
		(30 "In14.Cu" signal "GND6")
		(32 "In15.Cu" signal "IN6")
		(34 "In16.Cu" signal "GND7")
		(2 "B.Cu" signal "BOTTOM")
		(9 "F.Adhes" user "F.Adhesive")
		(11 "B.Adhes" user "B.Adhesive")
		(13 "F.Paste" user "Package Geometry/Pastemask Top")
		(15 "B.Paste" user "Package Geometry/Pastemask Bottom")
		(5 "F.SilkS" user "Ref Des/Silkscreen Top")
		(7 "B.SilkS" user "Ref Des/Silkscreen Bottom")
		(1 "F.Mask" user "Board Geometry/Soldermask Top")
		(3 "B.Mask" user "Board Geometry/Soldermask Bottom")
		(17 "Dwgs.User" user "User.Drawings")
		(19 "Cmts.User" user "User.Comments")
		(21 "Eco1.User" user "User.Eco1")
		(23 "Eco2.User" user "User.Eco2")
		(25 "Edge.Cuts" user "Board Geometry/Outline")
		(27 "Margin" user)
		(31 "F.CrtYd" user "Package Geometry/Place Bound Top")
		(29 "B.CrtYd" user "Package Geometry/Place Bound Bottom")
		(35 "F.Fab" user "Ref Des/Assembly Top")
		(33 "B.Fab" user "Ref Des/Assembly Bottom")
	)
	(footprint ""
		(layer "F.Cu")
		(at 6.673088 -373.44985 -90)
		(property "Reference" "PC6632"
			(at 4.41452 2.228088 0)
			(unlocked yes)
			(layer "F.SilkS")
			(effects
				(font
					(size 0.7874 0.5842)
					(thickness 0.1524)
				)
				(justify left)
			)
		)
		(property "Value" ""
			(at 0 0 270)
			(layer "F.Fab")
			(effects
				(font
					(size 1.27 1.27)
				)
			)
		)
		(duplicate_pad_numbers_are_jumpers no)
		(fp_line
			(start -1.988058 2.750058)
			(end 2.750058 2.750058)
			(stroke
				(width 0.1524)
				(type default)
			)
			(layer "F.SilkS")
		)
		(fp_line
			(start 2.750058 2.750058)
			(end 2.750058 0.9398)
			(stroke
				(width 0.1524)
				(type default)
			)
			(layer "F.SilkS")
		)
		(fp_line
			(start -2.750058 1.988058)
			(end -1.988058 2.750058)
			(stroke
				(width 0.1524)
				(type default)
			)
			(layer "F.SilkS")
		)
		(fp_line
			(start -2.750058 0.9398)
			(end -2.750058 1.988058)
			(stroke
				(width 0.1524)
				(type default)
			)
			(layer "F.SilkS")
		)
		(fp_line
			(start 2.750058 -0.9398)
			(end 2.750058 -2.750058)
			(stroke
				(width 0.1524)
				(type default)
			)
			(layer "F.SilkS")
		)
		(fp_line
			(start -2.750058 -1.988058)
			(end -2.750058 -0.9398)
			(stroke
				(width 0.1524)
				(type default)
			)
			(layer "F.SilkS")
		)
		(fp_line
			(start -1.988058 -2.750058)
			(end -2.750058 -1.988058)
			(stroke
				(width 0.1524)
				(type default)
			)
			(layer "F.SilkS")
		)
		(fp_line
			(start 2.750058 -2.750058)
			(end -1.988058 -2.750058)
			(stroke
				(width 0.1524)
				(type default)
			)
			(layer "F.SilkS")
		)
		(fp_line
			(start -2.750058 2.750058)
			(end 2.750058 2.750058)
			(stroke
				(width 0.1)
				(type default)
			)
			(layer "F.Fab")
		)
		(fp_line
			(start 2.750058 2.750058)
			(end 2.750058 -2.750058)
			(stroke
				(width 0.1)
				(type default)
			)
			(layer "F.Fab")
		)
		(fp_line
			(start -2.750058 -2.750058)
			(end -2.750058 2.750058)
			(stroke
				(width 0.1)
				(type default)
			)
			(layer "F.Fab")
		)
		(fp_line
			(start 2.750058 -2.750058)
			(end -2.750058 -2.750058)
			(stroke
				(width 0.1)
				(type default)
			)
			(layer "F.Fab")
		)
		(pad "1" smd rect
			(at -2.199894 0)
			(size 1.6002 3.0226)
			(layers "F.Cu" "F.Mask" "F.Paste")
			(net "P0V9_CPU1_RT_2D")
		)
		(pad "2" smd rect
			(at 2.199894 0)
			(size 1.6002 3.0226)
			(layers "F.Cu" "F.Mask" "F.Paste")
			(net "GND")
		)
	)
	(footprint ""
		(layer "F.Cu")
		(at 353.900232 -260.305042)
		(property "Reference" "C2141"
			(at 0 0 0)
			(layer "F.SilkS")
			(hide yes)
			(effects
				(font
					(size 1.27 1.27)
				)
			)
		)
		(property "Value" ""
			(at 0 0 0)
			(layer "F.Fab")
			(effects
				(font
					(size 1.27 1.27)
				)
			)
		)
		(duplicate_pad_numbers_are_jumpers no)
		(fp_line
			(start -0.7874 -0.4064)
			(end 0.7874 -0.4064)
			(stroke
				(width 0.1524)
				(type default)
			)
			(layer "F.SilkS")
		)
		(fp_line
			(start -0.7874 0.4064)
			(end -0.7874 -0.4064)
			(stroke
				(width 0.1524)
				(type default)
			)
			(layer "F.SilkS")
		)
		(fp_line
			(start 0.7874 -0.4064)
			(end 0.7874 0.4064)
			(stroke
				(width 0.1524)
				(type default)
			)
			(layer "F.SilkS")
		)
		(fp_line
			(start 0.7874 0.4064)
			(end -0.7874 0.4064)
			(stroke
				(width 0.1524)
				(type default)
			)
			(layer "F.SilkS")
		)
		(fp_line
			(start -0.67945 -0.305054)
			(end -0.12065 -0.305054)
			(stroke
				(width 0.1)
				(type default)
			)
			(layer "F.Fab")
		)
		(fp_line
			(start -0.67945 0.3048)
			(end -0.67945 -0.305054)
			(stroke
				(width 0.1)
				(type default)
			)
			(layer "F.Fab")
		)
		(fp_line
			(start -0.12065 -0.305054)
			(end -0.12065 -0.2794)
			(stroke
				(width 0.1)
				(type default)
			)
			(layer "F.Fab")
		)
		(fp_line
			(start -0.12065 -0.2794)
			(end 0.12065 -0.2794)
			(stroke
				(width 0.1)
				(type default)
			)
			(layer "F.Fab")
		)
		(fp_line
			(start -0.12065 0.2794)
			(end -0.12065 0.3048)
			(stroke
				(width 0.1)
				(type default)
			)
			(layer "F.Fab")
		)
		(fp_line
			(start -0.12065 0.3048)
			(end -0.67945 0.3048)
			(stroke
				(width 0.1)
				(type default)
			)
			(layer "F.Fab")
		)
		(fp_line
			(start 0.120396 0.2794)
			(end -0.12065 0.2794)
			(stroke
				(width 0.1)
				(type default)
			)
			(layer "F.Fab")
		)
		(fp_line
			(start 0.120396 0.3048)
			(end 0.120396 0.2794)
			(stroke
				(width 0.1)
				(type default)
			)
			(layer "F.Fab")
		)
		(fp_line
			(start 0.12065 -0.3048)
			(end 0.67945 -0.3048)
			(stroke
				(width 0.1)
				(type default)
			)
			(layer "F.Fab")
		)
		(fp_line
			(start 0.12065 -0.2794)
			(end 0.12065 -0.3048)
			(stroke
				(width 0.1)
				(type default)
			)
			(layer "F.Fab")
		)
		(fp_line
			(start 0.67945 -0.3048)
			(end 0.67945 0.3048)
			(stroke
				(width 0.1)
				(type default)
			)
			(layer "F.Fab")
		)
		(fp_line
			(start 0.67945 0.3048)
			(end 0.120396 0.3048)
			(stroke
				(width 0.1)
				(type default)
			)
			(layer "F.Fab")
		)
		(pad "1" smd circle
			(at -0.40005 0)
			(size 0 0)
			(layers "F.Cu" "F.Mask" "F.Paste")
			(net "PVDDIO_P0")
		)
		(pad "2" smd circle
			(at 0.40005 0)
			(size 0 0)
			(layers "F.Cu" "F.Mask" "F.Paste")
			(net "GND")
		)
	)
)
